# BASEBOARD_FAB2 (Tioga Pass) — schematic netlist excerpt (pin names and nets, part order shuffled) for the footprints in the layout excerpt that follows; sources: Cadence DE-HDL packaged netlist, KiCad conversion of Wiwynn_Tioga_Pass_MB.brd

C8T4  CAP_A  47UF 4V 20% X5R  pkg 0603V  page 225 : A = PVDDQ_GHJ ; B = GND
C5G79  CAP_A  22.0UF 4V 20% X6S  pkg 0603V  page 243 : A = PVDDQ_GHJ ; B = GND
C25W67  CAP  1.0UF 16V 10% X6S  pkg 0402  page 149 : A = VCC_VA_3V3 ; B = GND

(kicad_pcb
	(version 20260206)
	(generator "pcbnew")
	(generator_version "10.0")
	(general
		(thickness 1.6)
		(legacy_teardrops no)
	)
	(paper "A4")
	(title_block
		(title "Wiwynn_Tioga_Pass_MB.brd")
		(comment 1 "Tioga Pass / footprints 3739-3741 of 4770")
	)
	(layers
		(0 "F.Cu" signal "TOP")
		(4 "In1.Cu" signal "L2GND")
		(6 "In2.Cu" signal "L3")
		(8 "In3.Cu" signal "L4GND")
		(10 "In4.Cu" signal "L5")
		(12 "In5.Cu" signal "L6GND")
		(14 "In6.Cu" signal "L7VCC")
		(16 "In7.Cu" signal "L8VCC")
		(18 "In8.Cu" signal "L9GND")
		(20 "In9.Cu" signal "L10")
		(22 "In10.Cu" signal "L11GND")
		(24 "In11.Cu" signal "L12")
		(26 "In12.Cu" signal "L13GND")
		(2 "B.Cu" signal "BOTTOM")
		(9 "F.Adhes" user "F.Adhesive")
		(11 "B.Adhes" user "B.Adhesive")
		(13 "F.Paste" user "Package Geometry/Pastemask Top")
		(15 "B.Paste" user "Package Geometry/Pastemask Bottom")
		(5 "F.SilkS" user "Ref Des/Silkscreen Top")
		(7 "B.SilkS" user "Ref Des/Silkscreen Bottom")
		(1 "F.Mask" user "Board Geometry/Soldermask Top")
		(3 "B.Mask" user "Board Geometry/Soldermask Bottom")
		(17 "Dwgs.User" user "User.Drawings")
		(19 "Cmts.User" user "User.Comments")
		(21 "Eco1.User" user "User.Eco1")
		(23 "Eco2.User" user "User.Eco2")
		(25 "Edge.Cuts" user "Board Geometry/Outline")
		(27 "Margin" user)
		(31 "F.CrtYd" user "Package Geometry/Place Bound Top")
		(29 "B.CrtYd" user "Package Geometry/Place Bound Bottom")
		(35 "F.Fab" user "Ref Des/Assembly Top")
		(33 "B.Fab" user "Ref Des/Assembly Bottom")
	)
	(footprint ""
		(layer "B.Cu")
		(at 411.299914 -28.73756 90)
		(property "Reference" "C25W67"
			(at 0.8382 -0.67818 90)
			(unlocked yes)
			(layer "B.SilkS")
			(effects
				(font
					(size 0.4064 0.254)
					(thickness 0.1524)
				)
				(justify left mirror)
			)
		)
		(property "Value" ""
			(at 0 0 90)
			(layer "B.Fab")
			(effects
				(font
					(size 1.27 1.27)
				)
				(justify mirror)
			)
		)
		(duplicate_pad_numbers_are_jumpers no)
		(fp_poly
			(pts
				(xy -0.3048 -0.1016) (xy -0.3048 0.9906) (xy 0.3048 0.9906) (xy 0.3048 -0.1016)
			)
			(stroke
				(width 0)
				(type default)
			)
			(fill no)
			(layer "B.CrtYd")
		)
		(fp_line
			(start 0.3048 -0.1016)
			(end 0.3048 0.9906)
			(stroke
				(width 0.1)
				(type default)
			)
			(layer "B.Fab")
		)
		(fp_line
			(start -0.3048 -0.1016)
			(end 0.3048 -0.1016)
			(stroke
				(width 0.1)
				(type default)
			)
			(layer "B.Fab")
		)
		(fp_line
			(start 0.3048 0.9906)
			(end -0.3048 0.9906)
			(stroke
				(width 0.1)
				(type default)
			)
			(layer "B.Fab")
		)
		(fp_line
			(start -0.3048 0.9906)
			(end -0.3048 -0.1016)
			(stroke
				(width 0.1)
				(type default)
			)
			(layer "B.Fab")
		)
		(pad "1" smd rect
			(at 0 0 270)
			(size 0.508 0.508)
			(layers "B.Cu" "B.Mask" "B.Paste")
			(net "VCC_VA_3V3")
		)
		(pad "2" smd rect
			(at 0 0.889 270)
			(size 0.508 0.508)
			(layers "B.Cu" "B.Mask" "B.Paste")
			(net "GND")
		)
		(zone
			(layer "B.Cu")
			(hatch none 0.5)
			(connect_pads
				(clearance 0)
			)
			(min_thickness 0.25)
			(keepout
				(tracks allowed)
				(vias not_allowed)
				(pads allowed)
				(copperpour not_allowed)
				(footprints allowed)
			)
			(placement
				(enabled no)
				(sheetname "")
			)
			(fill
				(thermal_gap 0.5)
				(thermal_bridge_width 0.5)
				(island_removal_mode 0)
			)
			(polygon
				(pts
					(xy 411.553914 -28.99156) (xy 411.553914 -28.48356) (xy 411.934914 -28.48356) (xy 411.934914 -28.99156)
				)
			)
		)
		(zone
			(layer "B.Cu")
			(hatch none 0.5)
			(connect_pads
				(clearance 0)
			)
			(min_thickness 0.25)
			(keepout
				(tracks not_allowed)
				(vias allowed)
				(pads allowed)
				(copperpour not_allowed)
				(footprints allowed)
			)
			(placement
				(enabled no)
				(sheetname "")
			)
			(fill
				(thermal_gap 0.5)
				(thermal_bridge_width 0.5)
				(island_removal_mode 0)
			)
			(polygon
				(pts
					(xy 411.934914 -28.99156) (xy 411.934914 -28.48356) (xy 411.553914 -28.48356) (xy 411.553914 -28.99156)
				)
			)
		)
	)
	(footprint ""
		(layer "B.Cu")
		(at 80.731868 -12.954 -90)
		(property "Reference" "C5G79"
			(at -1.14681 0.76708 0)
			(unlocked yes)
			(layer "B.SilkS")
			(effects
				(font
					(size 0.7874 0.5842)
					(thickness 0.1524)
				)
				(justify mirror)
			)
		)
		(property "Value" ""
			(at 0 0 90)
			(layer "B.Fab")
			(effects
				(font
					(size 1.27 1.27)
				)
				(justify mirror)
			)
		)
		(duplicate_pad_numbers_are_jumpers no)
		(fp_rect
			(start 0.4953 1.6002)
			(end -0.4953 -0.2032)
			(stroke
				(width 0)
				(type default)
			)
			(fill no)
			(layer "B.CrtYd")
		)
		(fp_line
			(start -0.4953 1.6002)
			(end 0.4953 1.6002)
			(stroke
				(width 0.1)
				(type default)
			)
			(layer "B.Fab")
		)
		(fp_line
			(start 0.4953 1.6002)
			(end 0.4953 -0.2032)
			(stroke
				(width 0.1)
				(type default)
			)
			(layer "B.Fab")
		)
		(fp_line
			(start -0.4953 -0.2032)
			(end -0.4953 1.6002)
			(stroke
				(width 0.1)
				(type default)
			)
			(layer "B.Fab")
		)
		(fp_line
			(start 0.4953 -0.2032)
			(end -0.4953 -0.2032)
			(stroke
				(width 0.1)
				(type default)
			)
			(layer "B.Fab")
		)
		(pad "1" smd rect
			(at 0 0 90)
			(size 0.762 0.889)
			(layers "B.Cu" "B.Mask" "B.Paste")
			(net "PVDDQ_GHJ")
		)
		(pad "2" smd rect
			(at 0 1.397 90)
			(size 0.762 0.889)
			(layers "B.Cu" "B.Mask" "B.Paste")
			(net "GND")
		)
		(zone
			(layer "B.Cu")
			(hatch none 0.5)
			(connect_pads
				(clearance 0)
			)
			(min_thickness 0.25)
			(keepout
				(tracks not_allowed)
				(vias allowed)
				(pads allowed)
				(copperpour not_allowed)
				(footprints allowed)
			)
			(placement
				(enabled no)
				(sheetname "")
			)
			(fill
				(thermal_gap 0.5)
				(thermal_bridge_width 0.5)
				(island_removal_mode 0)
			)
			(polygon
				(pts
					(xy 79.779368 -12.573) (xy 80.287368 -12.573) (xy 80.287368 -13.335) (xy 79.779368 -13.335)
				)
			)
		)
	)
	(footprint ""
		(layer "B.Cu")
		(at 111.7727 -28.88234 90)
		(property "Reference" "C8T4"
			(at 0 0 90)
			(layer "B.SilkS")
			(hide yes)
			(effects
				(font
					(size 1.27 1.27)
				)
				(justify mirror)
			)
		)
		(property "Value" ""
			(at 0 0 90)
			(layer "B.Fab")
			(effects
				(font
					(size 1.27 1.27)
				)
				(justify mirror)
			)
		)
		(duplicate_pad_numbers_are_jumpers no)
		(fp_rect
			(start 0.500126 1.598422)
			(end -0.500126 -0.201422)
			(stroke
				(width 0)
				(type default)
			)
			(fill no)
			(layer "B.CrtYd")
		)
		(fp_line
			(start 0.500126 -0.201422)
			(end -0.500126 -0.201422)
			(stroke
				(width 0.1)
				(type default)
			)
			(layer "B.Fab")
		)
		(fp_line
			(start -0.500126 -0.201422)
			(end -0.500126 1.598422)
			(stroke
				(width 0.1)
				(type default)
			)
			(layer "B.Fab")
		)
		(fp_line
			(start 0.500126 1.598422)
			(end 0.500126 -0.201422)
			(stroke
				(width 0.1)
				(type default)
			)
			(layer "B.Fab")
		)
		(fp_line
			(start -0.500126 1.598422)
			(end 0.500126 1.598422)
			(stroke
				(width 0.1)
				(type default)
			)
			(layer "B.Fab")
		)
		(pad "1" smd rect
			(at 0 0)
			(size 0.889 0.9906)
			(layers "B.Cu" "B.Mask" "B.Paste")
			(net "PVDDQ_GHJ")
		)
		(pad "2" smd rect
			(at 0 1.397)
			(size 0.889 0.9906)
			(layers "B.Cu" "B.Mask" "B.Paste")
			(net "GND")
		)
		(zone
			(layer "B.Cu")
			(hatch none 0.5)
			(connect_pads
				(clearance 0)
			)
			(min_thickness 0.25)
			(keepout
				(tracks allowed)
				(vias not_allowed)
				(pads allowed)
				(copperpour not_allowed)
				(footprints allowed)
			)
			(placement
				(enabled no)
				(sheetname "")
			)
			(fill
				(thermal_gap 0.5)
				(thermal_bridge_width 0.5)
				(island_removal_mode 0)
			)
			(polygon
				(pts
					(xy 112.7252 -29.37764) (xy 112.2172 -29.37764) (xy 112.2172 -28.38704) (xy 112.7252 -28.38704)
				)
			)
		)
		(zone
			(layer "B.Cu")
			(hatch none 0.5)
			(connect_pads
				(clearance 0)
			)
			(min_thickness 0.25)
			(keepout
				(tracks not_allowed)
				(vias allowed)
				(pads allowed)
				(copperpour not_allowed)
				(footprints allowed)
			)
			(placement
				(enabled no)
				(sheetname "")
			)
			(fill
				(thermal_gap 0.5)
				(thermal_bridge_width 0.5)
				(island_removal_mode 0)
			)
			(polygon
				(pts
					(xy 112.7252 -29.37764) (xy 112.2172 -29.37764) (xy 112.2172 -28.38704) (xy 112.7252 -28.38704)
				)
			)
		)
	)
)
